# S9S_MB_2U (Grand Teton) — schematic netlist excerpt (pin names and nets, part order shuffled) for the footprints in the layout excerpt that follows; sources: Cadence DE-HDL packaged netlist, KiCad conversion of 03242023_DA0F0TMBIJ0_F0T_Motherboard_J_brd_V01_OCP.brd

PC1247  Q_CAP  22UF 16V 20% X6S  pkg C0805  page 281 : A = SW_P12V_PVCCIN_CPU0_FLT ; B = GND
C1957  Q_CAP  0.1UF 25V 10% X7R  pkg 0402  page 149 : A = P3V3_AUX ; B = GND
PC300  Q_CAP  100NF 50V 10% X7R  pkg C0402  page 267 : A = SW_PVCCIN_CPU0_BOOT2_R ; B = SW_PVCCIN_CPU0_BOOTR2

(kicad_pcb
	(version 20260206)
	(generator "pcbnew")
	(generator_version "10.0")
	(general
		(thickness 1.6)
		(legacy_teardrops no)
	)
	(paper "A4")
	(title_block
		(title "03242023_DA0F0TMBIJ0_F0T_Motherboard_J_brd_V01_OCP.brd")
		(comment 1 "Grand Teton / footprints 2201-2203 of 6105")
	)
	(layers
		(0 "F.Cu" signal "TOP")
		(4 "In1.Cu" signal "GND")
		(6 "In2.Cu" signal "IN1")
		(8 "In3.Cu" signal "GND1")
		(10 "In4.Cu" signal "IN2")
		(12 "In5.Cu" signal "GND2")
		(14 "In6.Cu" signal "IN3")
		(16 "In7.Cu" signal "GND3")
		(18 "In8.Cu" signal "VCC")
		(20 "In9.Cu" signal "VCC1")
		(22 "In10.Cu" signal "GND4")
		(24 "In11.Cu" signal "IN4")
		(26 "In12.Cu" signal "GND5")
		(28 "In13.Cu" signal "IN5")
		(30 "In14.Cu" signal "GND6")
		(32 "In15.Cu" signal "IN6")
		(34 "In16.Cu" signal "GND7")
		(2 "B.Cu" signal "BOTTOM")
		(9 "F.Adhes" user "F.Adhesive")
		(11 "B.Adhes" user "B.Adhesive")
		(13 "F.Paste" user "Package Geometry/Pastemask Top")
		(15 "B.Paste" user "Package Geometry/Pastemask Bottom")
		(5 "F.SilkS" user "Ref Des/Silkscreen Top")
		(7 "B.SilkS" user "Ref Des/Silkscreen Bottom")
		(1 "F.Mask" user "Board Geometry/Soldermask Top")
		(3 "B.Mask" user "Board Geometry/Soldermask Bottom")
		(17 "Dwgs.User" user "User.Drawings")
		(19 "Cmts.User" user "User.Comments")
		(21 "Eco1.User" user "User.Eco1")
		(23 "Eco2.User" user "User.Eco2")
		(25 "Edge.Cuts" user "Board Geometry/Outline")
		(27 "Margin" user)
		(31 "F.CrtYd" user "Package Geometry/Place Bound Top")
		(29 "B.CrtYd" user "Package Geometry/Place Bound Bottom")
		(35 "F.Fab" user "Ref Des/Assembly Top")
		(33 "B.Fab" user "Ref Des/Assembly Bottom")
	)
	(footprint ""
		(layer "F.Cu")
		(at 374.336056 -352.812858)
		(property "Reference" "PC1247"
			(at 0 0 0)
			(layer "F.SilkS")
			(hide yes)
			(effects
				(font
					(size 1.27 1.27)
				)
			)
		)
		(property "Value" ""
			(at 0 0 0)
			(layer "F.Fab")
			(effects
				(font
					(size 1.27 1.27)
				)
			)
		)
		(duplicate_pad_numbers_are_jumpers no)
		(fp_line
			(start -1.524 -0.762)
			(end 1.524 -0.762)
			(stroke
				(width 0.1524)
				(type default)
			)
			(layer "F.SilkS")
		)
		(fp_line
			(start -1.524 0.762)
			(end -1.524 -0.762)
			(stroke
				(width 0.1524)
				(type default)
			)
			(layer "F.SilkS")
		)
		(fp_line
			(start 1.524 -0.762)
			(end 1.524 0.762)
			(stroke
				(width 0.1524)
				(type default)
			)
			(layer "F.SilkS")
		)
		(fp_line
			(start 1.524 0.762)
			(end -1.524 0.762)
			(stroke
				(width 0.1524)
				(type default)
			)
			(layer "F.SilkS")
		)
		(fp_line
			(start -1.1049 -0.724916)
			(end -1.1049 0.724916)
			(stroke
				(width 0.1)
				(type default)
			)
			(layer "F.Fab")
		)
		(fp_line
			(start -1.1049 0.724916)
			(end 1.1049 0.724916)
			(stroke
				(width 0.1)
				(type default)
			)
			(layer "F.Fab")
		)
		(fp_line
			(start 1.1049 -0.724916)
			(end -1.1049 -0.724916)
			(stroke
				(width 0.1)
				(type default)
			)
			(layer "F.Fab")
		)
		(fp_line
			(start 1.1049 0.724916)
			(end 1.1049 -0.724916)
			(stroke
				(width 0.1)
				(type default)
			)
			(layer "F.Fab")
		)
		(pad "1" smd rect
			(at -0.889 0 180)
			(size 1.016 1.27)
			(layers "F.Cu" "F.Mask" "F.Paste")
			(net "SW_P12V_PVCCIN_CPU0_FLT")
		)
		(pad "2" smd rect
			(at 0.889 0 180)
			(size 1.016 1.27)
			(layers "F.Cu" "F.Mask" "F.Paste")
			(net "GND")
		)
	)
	(footprint ""
		(layer "F.Cu")
		(at 354.93071 -338.180172 -90)
		(property "Reference" "PC300"
			(at 0 0 270)
			(layer "F.SilkS")
			(hide yes)
			(effects
				(font
					(size 1.27 1.27)
				)
			)
		)
		(property "Value" ""
			(at 0 0 270)
			(layer "F.Fab")
			(effects
				(font
					(size 1.27 1.27)
				)
			)
		)
		(duplicate_pad_numbers_are_jumpers no)
		(fp_line
			(start -0.7874 0.4064)
			(end -0.7874 -0.4064)
			(stroke
				(width 0.1524)
				(type default)
			)
			(layer "F.SilkS")
		)
		(fp_line
			(start 0.7874 0.4064)
			(end -0.7874 0.4064)
			(stroke
				(width 0.1524)
				(type default)
			)
			(layer "F.SilkS")
		)
		(fp_line
			(start -0.7874 -0.4064)
			(end 0.7874 -0.4064)
			(stroke
				(width 0.1524)
				(type default)
			)
			(layer "F.SilkS")
		)
		(fp_line
			(start 0.7874 -0.4064)
			(end 0.7874 0.4064)
			(stroke
				(width 0.1524)
				(type default)
			)
			(layer "F.SilkS")
		)
		(fp_line
			(start -0.67945 0.3048)
			(end -0.67945 -0.305054)
			(stroke
				(width 0.1)
				(type default)
			)
			(layer "F.Fab")
		)
		(fp_line
			(start -0.12065 0.3048)
			(end -0.67945 0.3048)
			(stroke
				(width 0.1)
				(type default)
			)
			(layer "F.Fab")
		)
		(fp_line
			(start 0.120396 0.3048)
			(end 0.120396 0.2794)
			(stroke
				(width 0.1)
				(type default)
			)
			(layer "F.Fab")
		)
		(fp_line
			(start 0.67945 0.3048)
			(end 0.120396 0.3048)
			(stroke
				(width 0.1)
				(type default)
			)
			(layer "F.Fab")
		)
		(fp_line
			(start -0.12065 0.2794)
			(end -0.12065 0.3048)
			(stroke
				(width 0.1)
				(type default)
			)
			(layer "F.Fab")
		)
		(fp_line
			(start 0.120396 0.2794)
			(end -0.12065 0.2794)
			(stroke
				(width 0.1)
				(type default)
			)
			(layer "F.Fab")
		)
		(fp_line
			(start -0.12065 -0.2794)
			(end 0.12065 -0.2794)
			(stroke
				(width 0.1)
				(type default)
			)
			(layer "F.Fab")
		)
		(fp_line
			(start 0.12065 -0.2794)
			(end 0.12065 -0.3048)
			(stroke
				(width 0.1)
				(type default)
			)
			(layer "F.Fab")
		)
		(fp_line
			(start 0.12065 -0.3048)
			(end 0.67945 -0.3048)
			(stroke
				(width 0.1)
				(type default)
			)
			(layer "F.Fab")
		)
		(fp_line
			(start 0.67945 -0.3048)
			(end 0.67945 0.3048)
			(stroke
				(width 0.1)
				(type default)
			)
			(layer "F.Fab")
		)
		(fp_line
			(start -0.67945 -0.305054)
			(end -0.12065 -0.305054)
			(stroke
				(width 0.1)
				(type default)
			)
			(layer "F.Fab")
		)
		(fp_line
			(start -0.12065 -0.305054)
			(end -0.12065 -0.2794)
			(stroke
				(width 0.1)
				(type default)
			)
			(layer "F.Fab")
		)
		(pad "1" smd circle
			(at -0.40005 0 270)
			(size 0 0)
			(layers "F.Cu" "F.Mask" "F.Paste")
			(net "SW_PVCCIN_CPU0_BOOT2_R")
		)
		(pad "2" smd circle
			(at 0.40005 0 270)
			(size 0 0)
			(layers "F.Cu" "F.Mask" "F.Paste")
			(net "SW_PVCCIN_CPU0_BOOTR2")
		)
	)
	(footprint ""
		(layer "F.Cu")
		(at 29.13888 -427.192948 -90)
		(property "Reference" "C1957"
			(at 0 0 270)
			(layer "F.SilkS")
			(hide yes)
			(effects
				(font
					(size 1.27 1.27)
				)
			)
		)
		(property "Value" ""
			(at 0 0 270)
			(layer "F.Fab")
			(effects
				(font
					(size 1.27 1.27)
				)
			)
		)
		(duplicate_pad_numbers_are_jumpers no)
		(fp_line
			(start -0.7874 0.4064)
			(end -0.7874 -0.4064)
			(stroke
				(width 0.1524)
				(type default)
			)
			(layer "F.SilkS")
		)
		(fp_line
			(start 0.7874 0.4064)
			(end -0.7874 0.4064)
			(stroke
				(width 0.1524)
				(type default)
			)
			(layer "F.SilkS")
		)
		(fp_line
			(start -0.7874 -0.4064)
			(end 0.7874 -0.4064)
			(stroke
				(width 0.1524)
				(type default)
			)
			(layer "F.SilkS")
		)
		(fp_line
			(start 0.7874 -0.4064)
			(end 0.7874 0.4064)
			(stroke
				(width 0.1524)
				(type default)
			)
			(layer "F.SilkS")
		)
		(fp_line
			(start -0.67945 0.3048)
			(end -0.67945 -0.305054)
			(stroke
				(width 0.1)
				(type default)
			)
			(layer "F.Fab")
		)
		(fp_line
			(start -0.12065 0.3048)
			(end -0.67945 0.3048)
			(stroke
				(width 0.1)
				(type default)
			)
			(layer "F.Fab")
		)
		(fp_line
			(start 0.120396 0.3048)
			(end 0.120396 0.2794)
			(stroke
				(width 0.1)
				(type default)
			)
			(layer "F.Fab")
		)
		(fp_line
			(start 0.67945 0.3048)
			(end 0.120396 0.3048)
			(stroke
				(width 0.1)
				(type default)
			)
			(layer "F.Fab")
		)
		(fp_line
			(start -0.12065 0.2794)
			(end -0.12065 0.3048)
			(stroke
				(width 0.1)
				(type default)
			)
			(layer "F.Fab")
		)
		(fp_line
			(start 0.120396 0.2794)
			(end -0.12065 0.2794)
			(stroke
				(width 0.1)
				(type default)
			)
			(layer "F.Fab")
		)
		(fp_line
			(start -0.12065 -0.2794)
			(end 0.12065 -0.2794)
			(stroke
				(width 0.1)
				(type default)
			)
			(layer "F.Fab")
		)
		(fp_line
			(start 0.12065 -0.2794)
			(end 0.12065 -0.3048)
			(stroke
				(width 0.1)
				(type default)
			)
			(layer "F.Fab")
		)
		(fp_line
			(start 0.12065 -0.3048)
			(end 0.67945 -0.3048)
			(stroke
				(width 0.1)
				(type default)
			)
			(layer "F.Fab")
		)
		(fp_line
			(start 0.67945 -0.3048)
			(end 0.67945 0.3048)
			(stroke
				(width 0.1)
				(type default)
			)
			(layer "F.Fab")
		)
		(fp_line
			(start -0.67945 -0.305054)
			(end -0.12065 -0.305054)
			(stroke
				(width 0.1)
				(type default)
			)
			(layer "F.Fab")
		)
		(fp_line
			(start -0.12065 -0.305054)
			(end -0.12065 -0.2794)
			(stroke
				(width 0.1)
				(type default)
			)
			(layer "F.Fab")
		)
		(pad "1" smd circle
			(at -0.40005 0 270)
			(size 0 0)
			(layers "F.Cu" "F.Mask" "F.Paste")
			(net "P3V3_AUX")
		)
		(pad "2" smd circle
			(at 0.40005 0 270)
			(size 0 0)
			(layers "F.Cu" "F.Mask" "F.Paste")
			(net "GND")
		)
	)
)
